(kicad_pcb
	(version 20260206)
	(generator "pcbnew")
	(generator_version "10.0")
	(general
		(thickness 1.6)
		(legacy_teardrops no)
	)
	(paper "A4")
	(title_block
		(title "Bryce Canyon_SCC_16316-1_OCP.brd")
		(comment 1 "Bryce Canyon / footprints 1387-1394 of 1561")
	)
	(layers
		(0 "F.Cu" signal "TOP")
		(4 "In1.Cu" signal "L2GND")
		(6 "In2.Cu" signal "L3")
		(8 "In3.Cu" signal "L4VCC")
		(10 "In4.Cu" signal "L5VCC")
		(12 "In5.Cu" signal "L6")
		(14 "In6.Cu" signal "L7GND")
		(2 "B.Cu" signal "BOTTOM")
		(9 "F.Adhes" user "F.Adhesive")
		(11 "B.Adhes" user "B.Adhesive")
		(13 "F.Paste" user "Package Geometry/Pastemask Top")
		(15 "B.Paste" user "Package Geometry/Pastemask Bottom")
		(5 "F.SilkS" user "Ref Des/Silkscreen Top")
		(7 "B.SilkS" user "Ref Des/Silkscreen Bottom")
		(1 "F.Mask" user "Board Geometry/Soldermask Top")
		(3 "B.Mask" user "Board Geometry/Soldermask Bottom")
		(17 "Dwgs.User" user "User.Drawings")
		(19 "Cmts.User" user "User.Comments")
		(21 "Eco1.User" user "User.Eco1")
		(23 "Eco2.User" user "User.Eco2")
		(25 "Edge.Cuts" user "Board Geometry/Outline")
		(27 "Margin" user)
		(31 "F.CrtYd" user "Package Geometry/Place Bound Top")
		(29 "B.CrtYd" user "Package Geometry/Place Bound Bottom")
		(35 "F.Fab" user "Ref Des/Assembly Top")
		(33 "B.Fab" user "Ref Des/Assembly Bottom")
	)
	(footprint ""
		(layer "B.Cu")
		(at 183.668416 -83.728052 90)
		(property "Reference" "C659"
			(at 0 0 90)
			(layer "B.SilkS")
			(hide yes)
			(effects
				(font
					(size 1.27 1.27)
				)
				(justify mirror)
			)
		)
		(property "Value" "SC6K8P50V2KX-GP"
			(at -1.1811 -2.7051 90)
			(unlocked yes)
			(layer "B.Fab")
			(hide yes)
			(effects
				(font
					(size 1.016 1.016)
					(thickness 0.1524)
				)
				(justify mirror)
			)
		)
		(property "Device Type" "C402H22"
			(at -1.1811 -4.2291 90)
			(unlocked yes)
			(layer "B.Fab")
			(hide yes)
			(effects
				(font
					(size 1.016 1.016)
					(thickness 0.1524)
				)
				(justify mirror)
			)
		)
		(duplicate_pad_numbers_are_jumpers no)
		(fp_rect
			(start 0.4318 0.9525)
			(end -0.4318 -0.9525)
			(stroke
				(width 0)
				(type default)
			)
			(fill no)
			(layer "B.CrtYd")
		)
		(fp_rect
			(start 0.4318 0.9525)
			(end -0.4318 -0.9525)
			(stroke
				(width 0)
				(type default)
			)
			(fill no)
			(layer "B.Fab")
		)
		(pad "1" smd custom
			(at 0 -0.4445 270)
			(size 0.1524 0.1524)
			(layers "B.Cu" "B.Mask" "B.Paste")
			(net "P0V975")
			(options
				(clearance outline)
				(anchor circle)
			)
			(primitives
				(gr_poly
					(pts
						(arc
							(start 0.3048 0.2032)
							(mid 0.275042 0.275042)
							(end 0.2032 0.3048)
						)
						(arc
							(start -0.2032 0.3048)
							(mid -0.275042 0.275042)
							(end -0.3048 0.2032)
						)
						(arc
							(start -0.3048 -0.2032)
							(mid -0.275042 -0.275042)
							(end -0.2032 -0.3048)
						)
						(arc
							(start 0.2032 -0.3048)
							(mid 0.275042 -0.275042)
							(end 0.3048 -0.2032)
						)
					)
					(width 0)
					(fill yes)
				)
			)
		)
		(pad "2" smd custom
			(at 0 0.4445 270)
			(size 0.1524 0.1524)
			(layers "B.Cu" "B.Mask" "B.Paste")
			(net "GND")
			(options
				(clearance outline)
				(anchor circle)
			)
			(primitives
				(gr_poly
					(pts
						(arc
							(start 0.3048 0.2032)
							(mid 0.275042 0.275042)
							(end 0.2032 0.3048)
						)
						(arc
							(start -0.2032 0.3048)
							(mid -0.275042 0.275042)
							(end -0.3048 0.2032)
						)
						(arc
							(start -0.3048 -0.2032)
							(mid -0.275042 -0.275042)
							(end -0.2032 -0.3048)
						)
						(arc
							(start 0.2032 -0.3048)
							(mid 0.275042 -0.275042)
							(end 0.3048 -0.2032)
						)
					)
					(width 0)
					(fill yes)
				)
			)
		)
	)
	(footprint ""
		(layer "B.Cu")
		(at 172.890434 -34.120328 180)
		(property "Reference" "C391"
			(at 0 0 0)
			(layer "B.SilkS")
			(hide yes)
			(effects
				(font
					(size 1.27 1.27)
				)
				(justify mirror)
			)
		)
		(property "Value" "SCD1U6D3V1KX-GP"
			(at 2.8321 -1.7399 180)
			(unlocked yes)
			(layer "B.Fab")
			(hide yes)
			(effects
				(font
					(size 1.016 1.016)
					(thickness 0.1524)
				)
				(justify mirror)
			)
		)
		(property "Device Type" "C0201H13"
			(at 2.8321 -3.2639 180)
			(unlocked yes)
			(layer "B.Fab")
			(hide yes)
			(effects
				(font
					(size 1.016 1.016)
					(thickness 0.1524)
				)
				(justify mirror)
			)
		)
		(duplicate_pad_numbers_are_jumpers no)
		(fp_rect
			(start 0.2794 0.6477)
			(end -0.2794 -0.6477)
			(stroke
				(width 0)
				(type default)
			)
			(fill no)
			(layer "B.CrtYd")
		)
		(fp_rect
			(start 0.2794 0.6477)
			(end -0.2794 -0.6477)
			(stroke
				(width 0)
				(type default)
			)
			(fill no)
			(layer "B.Fab")
		)
		(pad "1" smd custom
			(at 0 -0.2794)
			(size 0.0762 0.0762)
			(layers "B.Cu" "B.Mask" "B.Paste")
			(net "PCE_AVDD")
			(options
				(clearance outline)
				(anchor circle)
			)
			(primitives
				(gr_poly
					(pts
						(arc
							(start 0.1524 0.127)
							(mid 0.137521 0.162921)
							(end 0.1016 0.1778)
						)
						(arc
							(start -0.1016 0.1778)
							(mid -0.137521 0.162921)
							(end -0.1524 0.127)
						)
						(arc
							(start -0.1524 -0.127)
							(mid -0.137521 -0.162921)
							(end -0.1016 -0.1778)
						)
						(arc
							(start 0.1016 -0.1778)
							(mid 0.137521 -0.162921)
							(end 0.1524 -0.127)
						)
					)
					(width 0)
					(fill yes)
				)
			)
		)
		(pad "2" smd custom
			(at 0 0.2794)
			(size 0.0762 0.0762)
			(layers "B.Cu" "B.Mask" "B.Paste")
			(net "GND")
			(options
				(clearance outline)
				(anchor circle)
			)
			(primitives
				(gr_poly
					(pts
						(arc
							(start 0.1524 0.127)
							(mid 0.137521 0.162921)
							(end 0.1016 0.1778)
						)
						(arc
							(start -0.1016 0.1778)
							(mid -0.137521 0.162921)
							(end -0.1524 0.127)
						)
						(arc
							(start -0.1524 -0.127)
							(mid -0.137521 -0.162921)
							(end -0.1016 -0.1778)
						)
						(arc
							(start 0.1016 -0.1778)
							(mid 0.137521 -0.162921)
							(end 0.1524 -0.127)
						)
					)
					(width 0)
					(fill yes)
				)
			)
		)
	)
	(footprint ""
		(layer "B.Cu")
		(at 114.1476 -84.455)
		(property "Reference" "R140"
			(at 0 0 0)
			(layer "B.SilkS")
			(hide yes)
			(effects
				(font
					(size 1.27 1.27)
				)
				(justify mirror)
			)
		)
		(property "Value" "34KR2F-GP"
			(at -0.064008 -3.993896 0)
			(unlocked yes)
			(layer "B.Fab")
			(hide yes)
			(effects
				(font
					(size 1.016 1.016)
					(thickness 0.1524)
				)
				(justify mirror)
			)
		)
		(property "Device Type" "R402H16"
			(at -0.064008 -5.517896 0)
			(unlocked yes)
			(layer "B.Fab")
			(hide yes)
			(effects
				(font
					(size 1.016 1.016)
					(thickness 0.1524)
				)
				(justify mirror)
			)
		)
		(duplicate_pad_numbers_are_jumpers no)
		(fp_line
			(start -0.508 -0.9398)
			(end 0.508 -0.9398)
			(stroke
				(width 0.1524)
				(type default)
			)
			(layer "B.SilkS")
		)
		(fp_line
			(start 0.508 -0.9398)
			(end 0.508 0.9398)
			(stroke
				(width 0.1524)
				(type default)
			)
			(layer "B.SilkS")
		)
		(fp_rect
			(start 0.508 0.9398)
			(end -0.508 -0.9398)
			(stroke
				(width 0)
				(type default)
			)
			(fill no)
			(layer "B.CrtYd")
		)
		(fp_rect
			(start 0.508 0.9398)
			(end -0.508 -0.9398)
			(stroke
				(width 0)
				(type default)
			)
			(fill no)
			(layer "B.Fab")
		)
		(pad "1" smd custom
			(at 0 -0.4445 180)
			(size 0.1397 0.1397)
			(layers "B.Cu" "B.Mask" "B.Paste")
			(net "P1V8_E")
			(options
				(clearance outline)
				(anchor circle)
			)
			(primitives
				(gr_poly
					(pts
						(arc
							(start -0.1778 0.2794)
							(mid -0.249642 0.249642)
							(end -0.2794 0.1778)
						)
						(arc
							(start -0.2794 -0.1778)
							(mid -0.249642 -0.249642)
							(end -0.1778 -0.2794)
						)
						(arc
							(start 0.1778 -0.2794)
							(mid 0.249642 -0.249642)
							(end 0.2794 -0.1778)
						)
						(arc
							(start 0.2794 0.1778)
							(mid 0.249642 0.249642)
							(end 0.1778 0.2794)
						)
					)
					(width 0)
					(fill yes)
				)
			)
		)
		(pad "2" smd custom
			(at 0 0.4445 180)
			(size 0.1397 0.1397)
			(layers "B.Cu" "B.Mask" "B.Paste")
			(net "EXP_XM_BUSY_N")
			(options
				(clearance outline)
				(anchor circle)
			)
			(primitives
				(gr_poly
					(pts
						(arc
							(start -0.1778 0.2794)
							(mid -0.249642 0.249642)
							(end -0.2794 0.1778)
						)
						(arc
							(start -0.2794 -0.1778)
							(mid -0.249642 -0.249642)
							(end -0.1778 -0.2794)
						)
						(arc
							(start 0.1778 -0.2794)
							(mid 0.249642 -0.249642)
							(end 0.2794 -0.1778)
						)
						(arc
							(start 0.2794 0.1778)
							(mid 0.249642 0.249642)
							(end 0.1778 0.2794)
						)
					)
					(width 0)
					(fill yes)
				)
			)
		)
	)
	(footprint ""
		(layer "B.Cu")
		(at 166.624 -59.6138 90)
		(property "Reference" "C353"
			(at 0 0 90)
			(layer "B.SilkS")
			(hide yes)
			(effects
				(font
					(size 1.27 1.27)
				)
				(justify mirror)
			)
		)
		(property "Value" "SC1U16V2KX-7-GP"
			(at -1.7526 -1.6002 90)
			(unlocked yes)
			(layer "B.Fab")
			(hide yes)
			(effects
				(font
					(size 1.016 1.016)
					(thickness 0.1524)
				)
				(justify mirror)
			)
		)
		(property "Device Type" "C402-TO0D2H24"
			(at -1.7526 -3.1242 90)
			(unlocked yes)
			(layer "B.Fab")
			(hide yes)
			(effects
				(font
					(size 1.016 1.016)
					(thickness 0.1524)
				)
				(justify mirror)
			)
		)
		(duplicate_pad_numbers_are_jumpers no)
		(fp_rect
			(start 0.4826 0.889)
			(end -0.4826 -0.889)
			(stroke
				(width 0)
				(type default)
			)
			(fill no)
			(layer "B.CrtYd")
		)
		(fp_rect
			(start 0.4826 0.889)
			(end -0.4826 -0.889)
			(stroke
				(width 0)
				(type default)
			)
			(fill no)
			(layer "B.Fab")
		)
		(pad "1" smd custom
			(at 0 -0.4572 270)
			(size 0.1524 0.1524)
			(layers "B.Cu" "B.Mask" "B.Paste")
			(net "HM40ADC_VDDA")
			(options
				(clearance outline)
				(anchor circle)
			)
			(primitives
				(gr_poly
					(pts
						(arc
							(start -0.254 -0.3048)
							(mid -0.325842 -0.275042)
							(end -0.3556 -0.2032)
						)
						(arc
							(start -0.3556 0.2032)
							(mid -0.325842 0.275042)
							(end -0.254 0.3048)
						)
						(arc
							(start 0.254 0.3048)
							(mid 0.325842 0.275042)
							(end 0.3556 0.2032)
						)
						(arc
							(start 0.3556 -0.2032)
							(mid 0.325842 -0.275042)
							(end 0.254 -0.3048)
						)
					)
					(width 0)
					(fill yes)
				)
			)
		)
		(pad "2" smd custom
			(at 0 0.4572 270)
			(size 0.1524 0.1524)
			(layers "B.Cu" "B.Mask" "B.Paste")
			(net "GND")
			(options
				(clearance outline)
				(anchor circle)
			)
			(primitives
				(gr_poly
					(pts
						(arc
							(start -0.254 -0.3048)
							(mid -0.325842 -0.275042)
							(end -0.3556 -0.2032)
						)
						(arc
							(start -0.3556 0.2032)
							(mid -0.325842 0.275042)
							(end -0.254 0.3048)
						)
						(arc
							(start 0.254 0.3048)
							(mid 0.325842 0.275042)
							(end 0.3556 0.2032)
						)
						(arc
							(start 0.3556 -0.2032)
							(mid 0.325842 -0.275042)
							(end 0.254 -0.3048)
						)
					)
					(width 0)
					(fill yes)
				)
			)
		)
	)
	(footprint ""
		(layer "B.Cu")
		(at 89.472516 -67.472814 180)
		(property "Reference" "L3"
			(at 0 0 0)
			(layer "B.SilkS")
			(hide yes)
			(effects
				(font
					(size 1.27 1.27)
				)
				(justify mirror)
			)
		)
		(property "Value" "MPZ2012S601AT-GP"
			(at 0 -4.2418 180)
			(unlocked yes)
			(layer "B.Fab")
			(hide yes)
			(effects
				(font
					(size 1.016 1.016)
					(thickness 0.1524)
				)
				(justify mirror)
			)
		)
		(property "Device Type" "L805H42"
			(at 0 -5.7912 180)
			(unlocked yes)
			(layer "B.Fab")
			(hide yes)
			(effects
				(font
					(size 1.016 1.016)
					(thickness 0.1524)
				)
				(justify mirror)
			)
		)
		(duplicate_pad_numbers_are_jumpers no)
		(fp_line
			(start 0.889 1.7018)
			(end 0.889 -1.7018)
			(stroke
				(width 0.1524)
				(type default)
			)
			(layer "B.SilkS")
		)
		(fp_line
			(start 0.889 -1.7018)
			(end -0.889 -1.7018)
			(stroke
				(width 0.1524)
				(type default)
			)
			(layer "B.SilkS")
		)
		(fp_line
			(start -0.889 1.7018)
			(end 0.889 1.7018)
			(stroke
				(width 0.1524)
				(type default)
			)
			(layer "B.SilkS")
		)
		(fp_line
			(start -0.889 -1.7018)
			(end -0.889 1.7018)
			(stroke
				(width 0.1524)
				(type default)
			)
			(layer "B.SilkS")
		)
		(fp_rect
			(start 0.9652 1.778)
			(end -0.9652 -1.778)
			(stroke
				(width 0)
				(type default)
			)
			(fill no)
			(layer "B.CrtYd")
		)
		(fp_rect
			(start 0.9652 1.778)
			(end -0.9652 -1.778)
			(stroke
				(width 0)
				(type default)
			)
			(fill no)
			(layer "B.Fab")
		)
		(pad "1" smd rect
			(at 0 -0.9652)
			(size 1.397 1.143)
			(layers "B.Cu" "B.Mask" "B.Paste")
			(net "PLLDDR_VDDA18")
		)
		(pad "2" smd rect
			(at 0 0.9652)
			(size 1.397 1.143)
			(layers "B.Cu" "B.Mask" "B.Paste")
			(net "P1V8_E")
		)
	)
	(footprint ""
		(layer "B.Cu")
		(at 130.433318 -87.260684 180)
		(property "Reference" "R43"
			(at 0 0 0)
			(layer "B.SilkS")
			(hide yes)
			(effects
				(font
					(size 1.27 1.27)
				)
				(justify mirror)
			)
		)
		(property "Value" "4K7R2F-GP"
			(at -0.064008 -3.993896 180)
			(unlocked yes)
			(layer "B.Fab")
			(hide yes)
			(effects
				(font
					(size 1.016 1.016)
					(thickness 0.1524)
				)
				(justify mirror)
			)
		)
		(property "Device Type" "R402H16"
			(at -0.064008 -5.517896 180)
			(unlocked yes)
			(layer "B.Fab")
			(hide yes)
			(effects
				(font
					(size 1.016 1.016)
					(thickness 0.1524)
				)
				(justify mirror)
			)
		)
		(duplicate_pad_numbers_are_jumpers no)
		(fp_line
			(start 0.508 -0.9398)
			(end 0.508 0.9398)
			(stroke
				(width 0.1524)
				(type default)
			)
			(layer "B.SilkS")
		)
		(fp_line
			(start -0.508 -0.9398)
			(end 0.508 -0.9398)
			(stroke
				(width 0.1524)
				(type default)
			)
			(layer "B.SilkS")
		)
		(fp_rect
			(start 0.508 0.9398)
			(end -0.508 -0.9398)
			(stroke
				(width 0)
				(type default)
			)
			(fill no)
			(layer "B.CrtYd")
		)
		(fp_rect
			(start 0.508 0.9398)
			(end -0.508 -0.9398)
			(stroke
				(width 0)
				(type default)
			)
			(fill no)
			(layer "B.Fab")
		)
		(pad "1" smd custom
			(at 0 -0.4445)
			(size 0.1397 0.1397)
			(layers "B.Cu" "B.Mask" "B.Paste")
			(net "EXP_SIO_D_OUT")
			(options
				(clearance outline)
				(anchor circle)
			)
			(primitives
				(gr_poly
					(pts
						(arc
							(start -0.1778 0.2794)
							(mid -0.249642 0.249642)
							(end -0.2794 0.1778)
						)
						(arc
							(start -0.2794 -0.1778)
							(mid -0.249642 -0.249642)
							(end -0.1778 -0.2794)
						)
						(arc
							(start 0.1778 -0.2794)
							(mid 0.249642 -0.249642)
							(end 0.2794 -0.1778)
						)
						(arc
							(start 0.2794 0.1778)
							(mid 0.249642 0.249642)
							(end 0.1778 0.2794)
						)
					)
					(width 0)
					(fill yes)
				)
			)
		)
		(pad "2" smd custom
			(at 0 0.4445)
			(size 0.1397 0.1397)
			(layers "B.Cu" "B.Mask" "B.Paste")
			(net "P1V8_E")
			(options
				(clearance outline)
				(anchor circle)
			)
			(primitives
				(gr_poly
					(pts
						(arc
							(start -0.1778 0.2794)
							(mid -0.249642 0.249642)
							(end -0.2794 0.1778)
						)
						(arc
							(start -0.2794 -0.1778)
							(mid -0.249642 -0.249642)
							(end -0.1778 -0.2794)
						)
						(arc
							(start 0.1778 -0.2794)
							(mid 0.249642 -0.249642)
							(end 0.2794 -0.1778)
						)
						(arc
							(start 0.2794 0.1778)
							(mid 0.249642 0.249642)
							(end 0.1778 0.2794)
						)
					)
					(width 0)
					(fill yes)
				)
			)
		)
	)
	(footprint ""
		(layer "B.Cu")
		(at 171.437808 -39.22141 -90)
		(property "Reference" "C447"
			(at 0 0 90)
			(layer "B.SilkS")
			(hide yes)
			(effects
				(font
					(size 1.27 1.27)
				)
				(justify mirror)
			)
		)
		(property "Value" "SC1KP50V2KX-1GP"
			(at -1.1811 -2.7051 270)
			(unlocked yes)
			(layer "B.Fab")
			(hide yes)
			(effects
				(font
					(size 1.016 1.016)
					(thickness 0.1524)
				)
				(justify mirror)
			)
		)
		(property "Device Type" "C402H22"
			(at -1.1811 -4.2291 270)
			(unlocked yes)
			(layer "B.Fab")
			(hide yes)
			(effects
				(font
					(size 1.016 1.016)
					(thickness 0.1524)
				)
				(justify mirror)
			)
		)
		(duplicate_pad_numbers_are_jumpers no)
		(fp_rect
			(start 0.4318 0.9525)
			(end -0.4318 -0.9525)
			(stroke
				(width 0)
				(type default)
			)
			(fill no)
			(layer "B.CrtYd")
		)
		(fp_rect
			(start 0.4318 0.9525)
			(end -0.4318 -0.9525)
			(stroke
				(width 0)
				(type default)
			)
			(fill no)
			(layer "B.Fab")
		)
		(pad "1" smd custom
			(at 0 -0.4445 90)
			(size 0.1524 0.1524)
			(layers "B.Cu" "B.Mask" "B.Paste")
			(net "P0V975")
			(options
				(clearance outline)
				(anchor circle)
			)
			(primitives
				(gr_poly
					(pts
						(arc
							(start 0.3048 0.2032)
							(mid 0.275042 0.275042)
							(end 0.2032 0.3048)
						)
						(arc
							(start -0.2032 0.3048)
							(mid -0.275042 0.275042)
							(end -0.3048 0.2032)
						)
						(arc
							(start -0.3048 -0.2032)
							(mid -0.275042 -0.275042)
							(end -0.2032 -0.3048)
						)
						(arc
							(start 0.2032 -0.3048)
							(mid 0.275042 -0.275042)
							(end 0.3048 -0.2032)
						)
					)
					(width 0)
					(fill yes)
				)
			)
		)
		(pad "2" smd custom
			(at 0 0.4445 90)
			(size 0.1524 0.1524)
			(layers "B.Cu" "B.Mask" "B.Paste")
			(net "GND")
			(options
				(clearance outline)
				(anchor circle)
			)
			(primitives
				(gr_poly
					(pts
						(arc
							(start 0.3048 0.2032)
							(mid 0.275042 0.275042)
							(end 0.2032 0.3048)
						)
						(arc
							(start -0.2032 0.3048)
							(mid -0.275042 0.275042)
							(end -0.3048 0.2032)
						)
						(arc
							(start -0.3048 -0.2032)
							(mid -0.275042 -0.275042)
							(end -0.2032 -0.3048)
						)
						(arc
							(start 0.2032 -0.3048)
							(mid 0.275042 -0.275042)
							(end 0.3048 -0.2032)
						)
					)
					(width 0)
					(fill yes)
				)
			)
		)
	)
	(footprint ""
		(layer "B.Cu")
		(at 162.814762 -16.258286)
		(property "Reference" "R312"
			(at 0 0 0)
			(layer "B.SilkS")
			(hide yes)
			(effects
				(font
					(size 1.27 1.27)
				)
				(justify mirror)
			)
		)
		(property "Value" "10KR2F-2-GP"
			(at -0.064008 -3.993896 0)
			(unlocked yes)
			(layer "B.Fab")
			(hide yes)
			(effects
				(font
					(size 1.016 1.016)
					(thickness 0.1524)
				)
				(justify mirror)
			)
		)
		(property "Device Type" "R402H16"
			(at -0.064008 -5.517896 0)
			(unlocked yes)
			(layer "B.Fab")
			(hide yes)
			(effects
				(font
					(size 1.016 1.016)
					(thickness 0.1524)
				)
				(justify mirror)
			)
		)
		(duplicate_pad_numbers_are_jumpers no)
		(fp_line
			(start -0.508 -0.9398)
			(end 0.508 -0.9398)
			(stroke
				(width 0.1524)
				(type default)
			)
			(layer "B.SilkS")
		)
		(fp_line
			(start 0.508 -0.9398)
			(end 0.508 0.9398)
			(stroke
				(width 0.1524)
				(type default)
			)
			(layer "B.SilkS")
		)
		(fp_rect
			(start 0.508 0.9398)
			(end -0.508 -0.9398)
			(stroke
				(width 0)
				(type default)
			)
			(fill no)
			(layer "B.CrtYd")
		)
		(fp_rect
			(start 0.508 0.9398)
			(end -0.508 -0.9398)
			(stroke
				(width 0)
				(type default)
			)
			(fill no)
			(layer "B.Fab")
		)
		(pad "1" smd custom
			(at 0 -0.4445 180)
			(size 0.1397 0.1397)
			(layers "B.Cu" "B.Mask" "B.Paste")
			(net "P3V3")
			(options
				(clearance outline)
				(anchor circle)
			)
			(primitives
				(gr_poly
					(pts
						(arc
							(start -0.1778 0.2794)
							(mid -0.249642 0.249642)
							(end -0.2794 0.1778)
						)
						(arc
							(start -0.2794 -0.1778)
							(mid -0.249642 -0.249642)
							(end -0.1778 -0.2794)
						)
						(arc
							(start 0.1778 -0.2794)
							(mid 0.249642 -0.249642)
							(end 0.2794 -0.1778)
						)
						(arc
							(start 0.2794 0.1778)
							(mid 0.249642 0.249642)
							(end 0.1778 0.2794)
						)
					)
					(width 0)
					(fill yes)
				)
			)
		)
		(pad "2" smd custom
			(at 0 0.4445 180)
			(size 0.1397 0.1397)
			(layers "B.Cu" "B.Mask" "B.Paste")
			(net "LS_EN_N")
			(options
				(clearance outline)
				(anchor circle)
			)
			(primitives
				(gr_poly
					(pts
						(arc
							(start -0.1778 0.2794)
							(mid -0.249642 0.249642)
							(end -0.2794 0.1778)
						)
						(arc
							(start -0.2794 -0.1778)
							(mid -0.249642 -0.249642)
							(end -0.1778 -0.2794)
						)
						(arc
							(start 0.1778 -0.2794)
							(mid 0.249642 -0.249642)
							(end 0.2794 -0.1778)
						)
						(arc
							(start 0.2794 0.1778)
							(mid 0.249642 0.249642)
							(end 0.1778 0.2794)
						)
					)
					(width 0)
					(fill yes)
				)
			)
		)
	)
)
